(kicad_pcb
	(version 20260206)
	(generator "pcbnew")
	(generator_version "10.0")
	(general
		(thickness 1.6)
		(legacy_teardrops no)
	)
	(paper "A4")
	(title_block
		(title "fcb — 12433-1M.1206WZS1330.brd")
		(comment 1 "Open Vault / Knox (Wiwynn) / footprints 29-34 of 495")
	)
	(layers
		(0 "F.Cu" signal "TOP")
		(4 "In1.Cu" signal "L2GND")
		(6 "In2.Cu" signal "L3VCC")
		(2 "B.Cu" signal "BOTTOM")
		(9 "F.Adhes" user "F.Adhesive")
		(11 "B.Adhes" user "B.Adhesive")
		(13 "F.Paste" user "Package Geometry/Pastemask Top")
		(15 "B.Paste" user "Package Geometry/Pastemask Bottom")
		(5 "F.SilkS" user "Ref Des/Silkscreen Top")
		(7 "B.SilkS" user "Ref Des/Silkscreen Bottom")
		(1 "F.Mask" user "Board Geometry/Soldermask Top")
		(3 "B.Mask" user "Board Geometry/Soldermask Bottom")
		(17 "Dwgs.User" user "User.Drawings")
		(19 "Cmts.User" user "User.Comments")
		(21 "Eco1.User" user "User.Eco1")
		(23 "Eco2.User" user "User.Eco2")
		(25 "Edge.Cuts" user "Board Geometry/Outline")
		(27 "Margin" user)
		(31 "F.CrtYd" user "Package Geometry/Place Bound Top")
		(29 "B.CrtYd" user "Package Geometry/Place Bound Bottom")
		(35 "F.Fab" user "Ref Des/Assembly Top")
		(33 "B.Fab" user "Ref Des/Assembly Bottom")
	)
	(footprint ""
		(layer "F.Cu")
		(at 21.844 -202.7936 -90)
		(property "Reference" "TC15"
			(at 0 0 270)
			(layer "F.SilkS")
			(hide yes)
			(effects
				(font
					(size 1.27 1.27)
				)
			)
		)
		(property "Value" "ST15U25VDM-1-GP"
			(at 0 -9.6012 270)
			(unlocked yes)
			(layer "F.Fab")
			(hide yes)
			(effects
				(font
					(size 1.016 1.016)
					(thickness 0.1524)
				)
			)
		)
		(property "Device Type" "CT7343H79"
			(at 0 -11.1252 270)
			(unlocked yes)
			(layer "F.Fab")
			(hide yes)
			(effects
				(font
					(size 1.016 1.016)
					(thickness 0.1524)
				)
			)
		)
		(duplicate_pad_numbers_are_jumpers no)
		(fp_line
			(start -2.286 4.8768)
			(end -2.286 2.032)
			(stroke
				(width 0.1524)
				(type default)
			)
			(layer "F.SilkS")
		)
		(fp_line
			(start 2.286 4.8768)
			(end -2.286 4.8768)
			(stroke
				(width 0.1524)
				(type default)
			)
			(layer "F.SilkS")
		)
		(fp_line
			(start 2.286 2.032)
			(end 2.286 4.8768)
			(stroke
				(width 0.1524)
				(type default)
			)
			(layer "F.SilkS")
		)
		(fp_line
			(start 2.286 -2.032)
			(end 2.286 -4.8768)
			(stroke
				(width 0.1524)
				(type default)
			)
			(layer "F.SilkS")
		)
		(fp_line
			(start 2.1082 -4.699)
			(end -2.1082 -4.699)
			(stroke
				(width 0.508)
				(type default)
			)
			(layer "F.SilkS")
		)
		(fp_line
			(start -2.286 -4.8768)
			(end -2.286 -2.032)
			(stroke
				(width 0.1524)
				(type default)
			)
			(layer "F.SilkS")
		)
		(fp_line
			(start 2.286 -4.8768)
			(end -2.286 -4.8768)
			(stroke
				(width 0.1524)
				(type default)
			)
			(layer "F.SilkS")
		)
		(fp_rect
			(start -2.1463 3.6449)
			(end 2.1463 -3.6449)
			(stroke
				(width 0)
				(type default)
			)
			(fill no)
			(layer "F.CrtYd")
		)
		(fp_poly
			(pts
				(xy -2.54 4.953) (xy -2.54 4.2926) (xy -3.81 4.2926) (xy -3.81 -4.2926) (xy -2.54 -4.2926) (xy -2.54 -4.953)
				(xy 2.54 -4.953) (xy 2.54 -4.2926) (xy 3.81 -4.2926) (xy 3.81 -1.6256) (xy 2.1463 -1.6256) (xy 2.1463 -3.6449)
				(xy -2.1463 -3.6449) (xy -2.1463 3.6449) (xy 2.1463 3.6449) (xy 2.1463 -1.6129) (xy 3.81 -1.6129)
				(xy 3.81 4.2926) (xy 2.54 4.2926) (xy 2.54 4.953)
			)
			(stroke
				(width 0)
				(type default)
			)
			(fill no)
			(layer "F.CrtYd")
		)
		(fp_rect
			(start -2.54 4.953)
			(end 2.54 -4.953)
			(stroke
				(width 0)
				(type default)
			)
			(fill no)
			(layer "F.Fab")
		)
		(fp_rect
			(start -3.81 4.2926)
			(end -2.54 -4.2926)
			(stroke
				(width 0)
				(type default)
			)
			(fill no)
			(layer "F.Fab")
		)
		(fp_rect
			(start 2.54 4.2926)
			(end 3.81 -4.2926)
			(stroke
				(width 0)
				(type default)
			)
			(fill no)
			(layer "F.Fab")
		)
		(pad "1" smd rect
			(at 0 -3.1496 270)
			(size 2.413 2.286)
			(layers "F.Cu" "F.Mask" "F.Paste")
			(net "P12V")
		)
		(pad "2" smd rect
			(at 0 3.1496 270)
			(size 2.413 2.286)
			(layers "F.Cu" "F.Mask" "F.Paste")
			(net "GND")
		)
		(zone
			(layer "F.Cu")
			(hatch none 0.5)
			(connect_pads
				(clearance 0)
			)
			(min_thickness 0.25)
			(keepout
				(tracks allowed)
				(vias not_allowed)
				(pads allowed)
				(copperpour not_allowed)
				(footprints allowed)
			)
			(placement
				(enabled no)
				(sheetname "")
			)
			(fill
				(thermal_gap 0.5)
				(thermal_bridge_width 0.5)
				(island_removal_mode 0)
			)
			(polygon
				(pts
					(xy 17.2466 -204.3049) (xy 17.2466 -201.2823) (xy 20.1422 -201.2823) (xy 20.4724 -201.2823) (xy 20.4724 -204.3049)
					(xy 20.1422 -204.3049)
				)
			)
		)
		(zone
			(layer "F.Cu")
			(hatch none 0.5)
			(connect_pads
				(clearance 0)
			)
			(min_thickness 0.25)
			(keepout
				(tracks allowed)
				(vias not_allowed)
				(pads allowed)
				(copperpour not_allowed)
				(footprints allowed)
			)
			(placement
				(enabled no)
				(sheetname "")
			)
			(fill
				(thermal_gap 0.5)
				(thermal_bridge_width 0.5)
				(island_removal_mode 0)
			)
			(polygon
				(pts
					(xy 23.5331 -201.2823) (xy 26.4414 -201.2823) (xy 26.4414 -204.3049) (xy 23.5458 -204.3049) (xy 23.2156 -204.3049)
					(xy 23.2156 -201.2823)
				)
			)
		)
	)
	(footprint ""
		(layer "F.Cu")
		(at 37.1602 -246.5324)
		(property "Reference" "U6"
			(at 0 0 0)
			(layer "F.SilkS")
			(hide yes)
			(effects
				(font
					(size 1.27 1.27)
				)
			)
		)
		(property "Value" "PCA9551PW-T-2GP-U"
			(at 0.127 -12.573 0)
			(unlocked yes)
			(layer "F.Fab")
			(hide yes)
			(effects
				(font
					(size 1.016 1.016)
					(thickness 0.1524)
				)
			)
		)
		(property "Device Type" "TSOIC16H44"
			(at 0.1016 -14.5796 0)
			(unlocked yes)
			(layer "F.Fab")
			(hide yes)
			(effects
				(font
					(size 1.016 1.016)
					(thickness 0.1524)
				)
			)
		)
		(duplicate_pad_numbers_are_jumpers no)
		(fp_line
			(start -3.0988 -1.778)
			(end -3.0988 1.778)
			(stroke
				(width 0.1524)
				(type default)
			)
			(layer "F.SilkS")
		)
		(fp_line
			(start -3.0988 -1.778)
			(end 2.3622 -1.778)
			(stroke
				(width 0.1524)
				(type default)
			)
			(layer "F.SilkS")
		)
		(fp_line
			(start -2.921 3.81)
			(end -2.921 1.778)
			(stroke
				(width 0.508)
				(type default)
			)
			(layer "F.SilkS")
		)
		(fp_line
			(start -2.54 0)
			(end -3.0988 -0.5588)
			(stroke
				(width 0.1524)
				(type default)
			)
			(layer "F.SilkS")
		)
		(fp_line
			(start -2.54 0)
			(end -3.0988 0.5588)
			(stroke
				(width 0.1524)
				(type default)
			)
			(layer "F.SilkS")
		)
		(fp_line
			(start 2.3622 -1.778)
			(end 2.3622 1.778)
			(stroke
				(width 0.1524)
				(type default)
			)
			(layer "F.SilkS")
		)
		(fp_line
			(start 2.3622 1.778)
			(end -2.921 1.778)
			(stroke
				(width 0.1524)
				(type default)
			)
			(layer "F.SilkS")
		)
		(fp_poly
			(pts
				(xy -2.4638 -1.778) (xy -2.4638 1.778) (xy 2.3622 1.778) (xy 2.3622 -1.778)
			)
			(stroke
				(width 0)
				(type default)
			)
			(fill yes)
			(layer "F.SilkS")
		)
		(fp_rect
			(start -3.175 4.064)
			(end 3.175 -4.064)
			(stroke
				(width 0)
				(type default)
			)
			(fill no)
			(layer "F.CrtYd")
		)
		(fp_poly
			(pts
				(xy -3.175 -4.064) (xy 3.175 -4.064) (xy 3.175 4.064) (xy -3.175 4.064)
			)
			(stroke
				(width 0)
				(type default)
			)
			(fill no)
			(layer "F.Fab")
		)
		(pad "1" smd rect
			(at -2.27584 2.8194)
			(size 0.3556 1.524)
			(layers "F.Cu" "F.Mask" "F.Paste")
			(net "LED_DRV_A0")
		)
		(pad "2" smd rect
			(at -1.6256 2.8194)
			(size 0.3556 1.524)
			(layers "F.Cu" "F.Mask" "F.Paste")
			(net "LED_DRV_A1")
		)
		(pad "3" smd rect
			(at -0.97536 2.8194)
			(size 0.3556 1.524)
			(layers "F.Cu" "F.Mask" "F.Paste")
			(net "LED_DRV_A2")
		)
		(pad "4" smd rect
			(at -0.32512 2.8194)
			(size 0.3556 1.524)
			(layers "F.Cu" "F.Mask" "F.Paste")
			(net "LED_DR_LED0")
		)
		(pad "5" smd rect
			(at 0.32512 2.8194)
			(size 0.3556 1.524)
			(layers "F.Cu" "F.Mask" "F.Paste")
			(net "LED_DR_LED1")
		)
		(pad "6" smd rect
			(at 0.97536 2.8194)
			(size 0.3556 1.524)
			(layers "F.Cu" "F.Mask" "F.Paste")
			(net "LED_DR_LED2")
		)
		(pad "7" smd rect
			(at 1.6256 2.8194)
			(size 0.3556 1.524)
			(layers "F.Cu" "F.Mask" "F.Paste")
			(net "LED_DR_LED3")
		)
		(pad "8" smd rect
			(at 2.27584 2.8194)
			(size 0.3556 1.524)
			(layers "F.Cu" "F.Mask" "F.Paste")
			(net "GND")
		)
		(pad "9" smd rect
			(at 2.27584 -2.8194)
			(size 0.3556 1.524)
			(layers "F.Cu" "F.Mask" "F.Paste")
			(net "LED_DR_LED4")
		)
		(pad "10" smd rect
			(at 1.6256 -2.8194)
			(size 0.3556 1.524)
			(layers "F.Cu" "F.Mask" "F.Paste")
			(net "LED_DR_LED5")
		)
		(pad "11" smd rect
			(at 0.97536 -2.8194)
			(size 0.3556 1.524)
			(layers "F.Cu" "F.Mask" "F.Paste")
			(net "LED_DR_LED6_RESERVE")
		)
		(pad "12" smd rect
			(at 0.32512 -2.8194)
			(size 0.3556 1.524)
			(layers "F.Cu" "F.Mask" "F.Paste")
			(net "LED_DR_LED7_RESERVE")
		)
		(pad "13" smd rect
			(at -0.32512 -2.8194)
			(size 0.3556 1.524)
			(layers "F.Cu" "F.Mask" "F.Paste")
			(net "LED_DRV_RST")
		)
		(pad "14" smd rect
			(at -0.97536 -2.8194)
			(size 0.3556 1.524)
			(layers "F.Cu" "F.Mask" "F.Paste")
			(net "I2C_C_SCL_LEDDRV")
		)
		(pad "15" smd rect
			(at -1.6256 -2.8194)
			(size 0.3556 1.524)
			(layers "F.Cu" "F.Mask" "F.Paste")
			(net "I2C_C_SDA_LEDDRV")
		)
		(pad "16" smd rect
			(at -2.27584 -2.8194)
			(size 0.3556 1.524)
			(layers "F.Cu" "F.Mask" "F.Paste")
			(net "P3V3")
		)
	)
	(footprint ""
		(layer "F.Cu")
		(at 26.15438 -376.08256 -90)
		(property "Reference" "PC2"
			(at 0 0 270)
			(layer "F.SilkS")
			(hide yes)
			(effects
				(font
					(size 1.27 1.27)
				)
			)
		)
		(property "Value" "SC10U25V5KX-GP"
			(at -0.0762 -6.1214 270)
			(unlocked yes)
			(layer "F.Fab")
			(hide yes)
			(effects
				(font
					(size 1.016 1.016)
					(thickness 0.1524)
				)
			)
		)
		(property "Device Type" "C805H56"
			(at -0.0762 -8.1534 270)
			(unlocked yes)
			(layer "F.Fab")
			(hide yes)
			(effects
				(font
					(size 1.016 1.016)
					(thickness 0.1524)
				)
			)
		)
		(duplicate_pad_numbers_are_jumpers no)
		(fp_line
			(start 0.635 0)
			(end -0.635 0)
			(stroke
				(width 0.508)
				(type default)
			)
			(layer "F.SilkS")
		)
		(fp_rect
			(start -0.9652 1.778)
			(end 0.9652 -1.778)
			(stroke
				(width 0)
				(type default)
			)
			(fill no)
			(layer "F.CrtYd")
		)
		(fp_poly
			(pts
				(xy -0.9652 -1.778) (xy 0.9652 -1.778) (xy 0.9652 1.778) (xy -0.9652 1.778)
			)
			(stroke
				(width 0)
				(type default)
			)
			(fill no)
			(layer "F.Fab")
		)
		(pad "1" smd rect
			(at 0 -0.9652 270)
			(size 1.397 1.143)
			(layers "F.Cu" "F.Mask" "F.Paste")
			(net "ADM1276_VCC")
		)
		(pad "2" smd rect
			(at 0 0.9652 270)
			(size 1.397 1.143)
			(layers "F.Cu" "F.Mask" "F.Paste")
			(net "GND")
		)
	)
	(footprint ""
		(layer "F.Cu")
		(at 28.702 -194.0814 90)
		(property "Reference" "C41"
			(at 0 0 90)
			(layer "F.SilkS")
			(hide yes)
			(effects
				(font
					(size 1.27 1.27)
				)
			)
		)
		(property "Value" "SCD1U50V3KX-GP"
			(at 0 -2.8194 90)
			(unlocked yes)
			(layer "F.Fab")
			(hide yes)
			(effects
				(font
					(size 1.016 1.016)
					(thickness 0.1524)
				)
			)
		)
		(property "Device Type" "C603H36"
			(at 0 -4.3434 90)
			(unlocked yes)
			(layer "F.Fab")
			(hide yes)
			(effects
				(font
					(size 1.016 1.016)
					(thickness 0.1524)
				)
			)
		)
		(duplicate_pad_numbers_are_jumpers no)
		(fp_line
			(start 0.508 0)
			(end -0.508 0)
			(stroke
				(width 0.2032)
				(type default)
			)
			(layer "F.SilkS")
		)
		(fp_rect
			(start -0.5842 1.3335)
			(end 0.5842 -1.3335)
			(stroke
				(width 0)
				(type default)
			)
			(fill no)
			(layer "F.CrtYd")
		)
		(fp_rect
			(start -0.5842 1.3335)
			(end 0.5842 -1.3335)
			(stroke
				(width 0)
				(type default)
			)
			(fill no)
			(layer "F.Fab")
		)
		(pad "1" smd custom
			(at 0 -0.762 90)
			(size 0.2159 0.2159)
			(layers "F.Cu" "F.Mask" "F.Paste")
			(net "P12V")
			(options
				(clearance outline)
				(anchor circle)
			)
			(primitives
				(gr_poly
					(pts
						(arc
							(start -0.3302 -0.4318)
							(mid -0.402042 -0.402042)
							(end -0.4318 -0.3302)
						)
						(arc
							(start -0.4318 0.3302)
							(mid -0.402042 0.402042)
							(end -0.3302 0.4318)
						)
						(arc
							(start 0.3302 0.4318)
							(mid 0.402042 0.402042)
							(end 0.4318 0.3302)
						)
						(arc
							(start 0.4318 -0.3302)
							(mid 0.402042 -0.402042)
							(end 0.3302 -0.4318)
						)
					)
					(width 0)
					(fill yes)
				)
			)
		)
		(pad "2" smd custom
			(at 0 0.762 90)
			(size 0.2159 0.2159)
			(layers "F.Cu" "F.Mask" "F.Paste")
			(net "GND")
			(options
				(clearance outline)
				(anchor circle)
			)
			(primitives
				(gr_poly
					(pts
						(arc
							(start -0.3302 -0.4318)
							(mid -0.402042 -0.402042)
							(end -0.4318 -0.3302)
						)
						(arc
							(start -0.4318 0.3302)
							(mid -0.402042 0.402042)
							(end -0.3302 0.4318)
						)
						(arc
							(start 0.3302 0.4318)
							(mid 0.402042 0.402042)
							(end 0.4318 0.3302)
						)
						(arc
							(start 0.4318 -0.3302)
							(mid 0.402042 -0.402042)
							(end 0.3302 -0.4318)
						)
					)
					(width 0)
					(fill yes)
				)
			)
		)
	)
	(footprint ""
		(layer "F.Cu")
		(at 12.5984 -146.1008)
		(property "Reference" "R74"
			(at 0 0 0)
			(layer "F.SilkS")
			(hide yes)
			(effects
				(font
					(size 1.27 1.27)
				)
			)
		)
		(property "Value" "10KR2F-2-GP"
			(at 0.064008 -3.993896 0)
			(unlocked yes)
			(layer "F.Fab")
			(hide yes)
			(effects
				(font
					(size 1.016 1.016)
					(thickness 0.1524)
				)
			)
		)
		(property "Device Type" "R402H16"
			(at 0.064008 -5.517896 0)
			(unlocked yes)
			(layer "F.Fab")
			(hide yes)
			(effects
				(font
					(size 1.016 1.016)
					(thickness 0.1524)
				)
			)
		)
		(duplicate_pad_numbers_are_jumpers no)
		(fp_line
			(start -0.508 -0.9398)
			(end -0.508 0.9398)
			(stroke
				(width 0.1524)
				(type default)
			)
			(layer "F.SilkS")
		)
		(fp_line
			(start 0.508 -0.9398)
			(end -0.508 -0.9398)
			(stroke
				(width 0.1524)
				(type default)
			)
			(layer "F.SilkS")
		)
		(fp_rect
			(start -0.508 0.9398)
			(end 0.508 -0.9398)
			(stroke
				(width 0)
				(type default)
			)
			(fill no)
			(layer "F.CrtYd")
		)
		(fp_rect
			(start -0.508 0.9398)
			(end 0.508 -0.9398)
			(stroke
				(width 0)
				(type default)
			)
			(fill no)
			(layer "F.Fab")
		)
		(pad "1" smd custom
			(at 0 -0.4445)
			(size 0.1397 0.1397)
			(layers "F.Cu" "F.Mask" "F.Paste")
			(net "FANIN_10")
			(options
				(clearance outline)
				(anchor circle)
			)
			(primitives
				(gr_poly
					(pts
						(arc
							(start -0.1778 -0.2794)
							(mid -0.249642 -0.249642)
							(end -0.2794 -0.1778)
						)
						(arc
							(start -0.2794 0.1778)
							(mid -0.249642 0.249642)
							(end -0.1778 0.2794)
						)
						(arc
							(start 0.1778 0.2794)
							(mid 0.249642 0.249642)
							(end 0.2794 0.1778)
						)
						(arc
							(start 0.2794 -0.1778)
							(mid 0.249642 -0.249642)
							(end 0.1778 -0.2794)
						)
					)
					(width 0)
					(fill yes)
				)
			)
		)
		(pad "2" smd custom
			(at 0 0.4445)
			(size 0.1397 0.1397)
			(layers "F.Cu" "F.Mask" "F.Paste")
			(net "GND")
			(options
				(clearance outline)
				(anchor circle)
			)
			(primitives
				(gr_poly
					(pts
						(arc
							(start -0.1778 -0.2794)
							(mid -0.249642 -0.249642)
							(end -0.2794 -0.1778)
						)
						(arc
							(start -0.2794 0.1778)
							(mid -0.249642 0.249642)
							(end -0.1778 0.2794)
						)
						(arc
							(start 0.1778 0.2794)
							(mid 0.249642 0.249642)
							(end 0.2794 0.1778)
						)
						(arc
							(start 0.2794 -0.1778)
							(mid 0.249642 -0.249642)
							(end 0.1778 -0.2794)
						)
					)
					(width 0)
					(fill yes)
				)
			)
		)
	)
	(footprint ""
		(layer "F.Cu")
		(at 27.305 -378.079)
		(property "Reference" "PR2"
			(at 0 0 0)
			(layer "F.SilkS")
			(hide yes)
			(effects
				(font
					(size 1.27 1.27)
				)
			)
		)
		(property "Value" "10R2F-L-GP"
			(at 0.064008 -3.993896 0)
			(unlocked yes)
			(layer "F.Fab")
			(hide yes)
			(effects
				(font
					(size 1.016 1.016)
					(thickness 0.1524)
				)
			)
		)
		(property "Device Type" "R402H14"
			(at 0.064008 -5.517896 0)
			(unlocked yes)
			(layer "F.Fab")
			(hide yes)
			(effects
				(font
					(size 1.016 1.016)
					(thickness 0.1524)
				)
			)
		)
		(duplicate_pad_numbers_are_jumpers no)
		(fp_line
			(start -0.508 -0.9398)
			(end -0.508 0.9398)
			(stroke
				(width 0.1524)
				(type default)
			)
			(layer "F.SilkS")
		)
		(fp_line
			(start 0.508 -0.9398)
			(end -0.508 -0.9398)
			(stroke
				(width 0.1524)
				(type default)
			)
			(layer "F.SilkS")
		)
		(fp_rect
			(start -0.508 0.9398)
			(end 0.508 -0.9398)
			(stroke
				(width 0)
				(type default)
			)
			(fill no)
			(layer "F.CrtYd")
		)
		(fp_rect
			(start -0.508 0.9398)
			(end 0.508 -0.9398)
			(stroke
				(width 0)
				(type default)
			)
			(fill no)
			(layer "F.Fab")
		)
		(pad "1" smd custom
			(at 0 -0.4445)
			(size 0.1397 0.1397)
			(layers "F.Cu" "F.Mask" "F.Paste")
			(net "P12V_AUX")
			(options
				(clearance outline)
				(anchor circle)
			)
			(primitives
				(gr_poly
					(pts
						(arc
							(start -0.1778 -0.2794)
							(mid -0.249642 -0.249642)
							(end -0.2794 -0.1778)
						)
						(arc
							(start -0.2794 0.1778)
							(mid -0.249642 0.249642)
							(end -0.1778 0.2794)
						)
						(arc
							(start 0.1778 0.2794)
							(mid 0.249642 0.249642)
							(end 0.2794 0.1778)
						)
						(arc
							(start 0.2794 -0.1778)
							(mid 0.249642 -0.249642)
							(end 0.1778 -0.2794)
						)
					)
					(width 0)
					(fill yes)
				)
			)
		)
		(pad "2" smd custom
			(at 0 0.4445)
			(size 0.1397 0.1397)
			(layers "F.Cu" "F.Mask" "F.Paste")
			(net "ADM1276_VCC")
			(options
				(clearance outline)
				(anchor circle)
			)
			(primitives
				(gr_poly
					(pts
						(arc
							(start -0.1778 -0.2794)
							(mid -0.249642 -0.249642)
							(end -0.2794 -0.1778)
						)
						(arc
							(start -0.2794 0.1778)
							(mid -0.249642 0.249642)
							(end -0.1778 0.2794)
						)
						(arc
							(start 0.1778 0.2794)
							(mid 0.249642 0.249642)
							(end 0.2794 0.1778)
						)
						(arc
							(start 0.2794 -0.1778)
							(mid 0.249642 -0.249642)
							(end 0.1778 -0.2794)
						)
					)
					(width 0)
					(fill yes)
				)
			)
		)
	)
)
